FILE_TYPE = CONNECTIVITY;
{Allegro Design Entry HDL 16.6-p007 (v16-6-112F) 10/10/2012}
"PAGE_NUMBER" = 134;
0"NC";
1"GND\g";
2"P3V3_STBY\g";
3"P1V05_PCH_STBY\g";
4"FM_THERMTRIP_DLY";
5"FM_THERMTRIP_DLY_R";
6"FM_PCH_LVC1_THERMTRIP_N";
7"RST_PLTRST_BUF_N";
8"FM_PCH_BMC_THERMTRIP_EXI_STRAP_N";
9"FM_PCH_BMC_THERMTRIP_N";
%"FET_N"
"8","(-2875,4400)","0","mstr_discrete","I10";
;
CDS_SEC"1"
PACK_TYPE"SOT23"
BOM_COST"SB"
SEC_TYPE"SOT23"
CDS_LIB"mstr_discrete"
SEC"1"
CDS_LOCATION"Q7D1"
ROOM"THERMTRIP_PCH"
LOCATION"Q7D1"
PART_NUMBER"C79254-001"
VALUE"2N7002"
MATERIAL"FET";
"GATE"
$PN"1"5;
"DRN"
$PN"3"6;
"SRC"
$PN"2"1;
%"RES"
"1","(-3950,4300)","0","mstr_discrete","I11";
;
CDS_SEC"1"
SEC_TYPE"0402"
CDS_LIB"mstr_discrete"
SEC"1"
CDS_LOCATION"R7D18"
ROOM"PROC_SIDEBAND"
LOCATION"R7D18"
PART_NUMBER"G21796-026"
VALUE"1.00K"
TOLERANCE"1%"
PACK_TYPE"0402"
MATERIAL"CHIP"
WATTAGE"1/16W";
"B"
$PN"2"5;
"A"
$PN"1"4;
%"GND"
"1","(-2875,3950)","0","mstr_symbols","I12";
;
VOLTAGE"0"
BOM_COST"SB"
CDS_LIB"mstr_symbols"
SIZE"1B"
BODY_TYPE"PLUMBING"
HDL_POWER"GND";
"A\NAC"1;
%"P3V3_STBY"
"1","(700,5200)","0","mstr_symbols","I2";
;
VOLTAGE"3.3V"
SIZE"1B"
CDS_LIB"mstr_symbols"
BODY_TYPE"PLUMBING"
HDL_POWER"P3V3_STBY";
"G\NAC"2;
%"RES"
"2","(700,4925)","0","mstr_discrete","I3";
;
CDS_SEC"1"
CDS_LOCATION"R2P17"
BOM_COST"SB"
CDS_LIB"mstr_discrete"
SEC_TYPE"0402"
SEC"1"
ROOM"THERMTRIP_PCH"
LOCATION"R2P17"
PART_NUMBER"G21796-072"
VALUE"4.75K"
TOLERANCE"1%"
PACK_TYPE"0402"
MATERIAL"CHIP"
WATTAGE"1/16W";
"A"
$PN"1"2;
"B"
$PN"2"9;
%"FET_N"
"8","(700,4375)","0","mstr_discrete","I4";
;
CDS_SEC"1"
CDS_LOCATION"Q8D2"
PACK_TYPE"SOT23"
CDS_LIB"mstr_discrete"
BOM_COST"SB"
SEC_TYPE"SOT23"
SEC"1"
ROOM"THERMTRIP_PCH"
LOCATION"Q8D2"
PART_NUMBER"C79254-001"
VALUE"2N7002"
MATERIAL"FET";
"GATE"
$PN"1"7;
"DRN"
$PN"3"9;
"SRC"
$PN"2"8;
%"P1V05_PCH_STBY"
"1","(-2875,5100)","0","mstr_symbols","I8";
;
VOLTAGE"1.05V"
CDS_LIB"mstr_symbols"
BODY_TYPE"PLUMBING"
HDL_POWER"P1V05_PCH_STBY";
"G\NAC"3;
%"RES"
"2","(-2875,4875)","0","mstr_discrete","I9";
;
CDS_SEC"1"
BOM_COST"SB"
SEC_TYPE"0402"
CDS_LIB"mstr_discrete"
SEC"1"
CDS_LOCATION"R7C21"
ROOM"THERMTRIP_PCH"
LOCATION"R7C21"
PART_NUMBER"G21796-016"
VALUE"10.0K"
TOLERANCE"1%"
PACK_TYPE"0402"
MATERIAL"CHIP"
WATTAGE"1/16W";
"A"
$PN"1"3;
"B"
$PN"2"6;
END.
